(kicad_pcb
	(version 20260206)
	(generator "pcbnew")
	(generator_version "10.0")
	(general
		(thickness 1.6)
		(legacy_teardrops no)
	)
	(paper "A4")
	(title_block
		(title "04192023_DAF0TMB3IC0_F0TG_MB_C_brd_V02_OCP.brd")
		(comment 1 "Grand Teton / footprints 2117-2122 of 8354")
	)
	(layers
		(0 "F.Cu" signal "TOP")
		(4 "In1.Cu" signal "GND")
		(6 "In2.Cu" signal "IN1")
		(8 "In3.Cu" signal "GND1")
		(10 "In4.Cu" signal "IN2")
		(12 "In5.Cu" signal "GND2")
		(14 "In6.Cu" signal "IN3")
		(16 "In7.Cu" signal "GND3")
		(18 "In8.Cu" signal "VCC")
		(20 "In9.Cu" signal "VCC1")
		(22 "In10.Cu" signal "GND4")
		(24 "In11.Cu" signal "IN4")
		(26 "In12.Cu" signal "GND5")
		(28 "In13.Cu" signal "IN5")
		(30 "In14.Cu" signal "GND6")
		(32 "In15.Cu" signal "IN6")
		(34 "In16.Cu" signal "GND7")
		(2 "B.Cu" signal "BOTTOM")
		(9 "F.Adhes" user "F.Adhesive")
		(11 "B.Adhes" user "B.Adhesive")
		(13 "F.Paste" user "Package Geometry/Pastemask Top")
		(15 "B.Paste" user "Package Geometry/Pastemask Bottom")
		(5 "F.SilkS" user "Ref Des/Silkscreen Top")
		(7 "B.SilkS" user "Ref Des/Silkscreen Bottom")
		(1 "F.Mask" user "Board Geometry/Soldermask Top")
		(3 "B.Mask" user "Board Geometry/Soldermask Bottom")
		(17 "Dwgs.User" user "User.Drawings")
		(19 "Cmts.User" user "User.Comments")
		(21 "Eco1.User" user "User.Eco1")
		(23 "Eco2.User" user "User.Eco2")
		(25 "Edge.Cuts" user "Board Geometry/Outline")
		(27 "Margin" user)
		(31 "F.CrtYd" user "Package Geometry/Place Bound Top")
		(29 "B.CrtYd" user "Package Geometry/Place Bound Bottom")
		(35 "F.Fab" user "Ref Des/Assembly Top")
		(33 "B.Fab" user "Ref Des/Assembly Bottom")
	)
	(footprint ""
		(layer "F.Cu")
		(at 367.991136 -179.50561 -90)
		(property "Reference" "PR495"
			(at 0 0 270)
			(layer "F.SilkS")
			(hide yes)
			(effects
				(font
					(size 1.27 1.27)
				)
			)
		)
		(property "Value" ""
			(at 0 0 270)
			(layer "F.Fab")
			(effects
				(font
					(size 1.27 1.27)
				)
			)
		)
		(duplicate_pad_numbers_are_jumpers no)
		(fp_line
			(start -0.7874 0.4064)
			(end -0.7874 -0.4064)
			(stroke
				(width 0.1524)
				(type default)
			)
			(layer "F.SilkS")
		)
		(fp_line
			(start 0.7874 0.4064)
			(end -0.7874 0.4064)
			(stroke
				(width 0.1524)
				(type default)
			)
			(layer "F.SilkS")
		)
		(fp_line
			(start -0.7874 -0.4064)
			(end 0.7874 -0.4064)
			(stroke
				(width 0.1524)
				(type default)
			)
			(layer "F.SilkS")
		)
		(fp_line
			(start 0.7874 -0.4064)
			(end 0.7874 0.4064)
			(stroke
				(width 0.1524)
				(type default)
			)
			(layer "F.SilkS")
		)
		(fp_line
			(start -0.67945 0.3048)
			(end -0.67945 -0.305054)
			(stroke
				(width 0.1)
				(type default)
			)
			(layer "F.Fab")
		)
		(fp_line
			(start -0.12065 0.3048)
			(end -0.67945 0.3048)
			(stroke
				(width 0.1)
				(type default)
			)
			(layer "F.Fab")
		)
		(fp_line
			(start 0.120396 0.3048)
			(end 0.120396 0.2794)
			(stroke
				(width 0.1)
				(type default)
			)
			(layer "F.Fab")
		)
		(fp_line
			(start 0.67945 0.3048)
			(end 0.120396 0.3048)
			(stroke
				(width 0.1)
				(type default)
			)
			(layer "F.Fab")
		)
		(fp_line
			(start -0.12065 0.2794)
			(end -0.12065 0.3048)
			(stroke
				(width 0.1)
				(type default)
			)
			(layer "F.Fab")
		)
		(fp_line
			(start 0.120396 0.2794)
			(end -0.12065 0.2794)
			(stroke
				(width 0.1)
				(type default)
			)
			(layer "F.Fab")
		)
		(fp_line
			(start -0.12065 -0.2794)
			(end 0.12065 -0.2794)
			(stroke
				(width 0.1)
				(type default)
			)
			(layer "F.Fab")
		)
		(fp_line
			(start 0.12065 -0.2794)
			(end 0.12065 -0.3048)
			(stroke
				(width 0.1)
				(type default)
			)
			(layer "F.Fab")
		)
		(fp_line
			(start 0.12065 -0.3048)
			(end 0.67945 -0.3048)
			(stroke
				(width 0.1)
				(type default)
			)
			(layer "F.Fab")
		)
		(fp_line
			(start 0.67945 -0.3048)
			(end 0.67945 0.3048)
			(stroke
				(width 0.1)
				(type default)
			)
			(layer "F.Fab")
		)
		(fp_line
			(start -0.67945 -0.305054)
			(end -0.12065 -0.305054)
			(stroke
				(width 0.1)
				(type default)
			)
			(layer "F.Fab")
		)
		(fp_line
			(start -0.12065 -0.305054)
			(end -0.12065 -0.2794)
			(stroke
				(width 0.1)
				(type default)
			)
			(layer "F.Fab")
		)
		(pad "1" smd circle
			(at -0.40005 0 270)
			(size 0 0)
			(layers "F.Cu" "F.Mask" "F.Paste")
			(net "SW_PVDDCR_CPU0_P0_SW1_RC")
		)
		(pad "2" smd circle
			(at 0.40005 0 270)
			(size 0 0)
			(layers "F.Cu" "F.Mask" "F.Paste")
			(net "GND")
		)
	)
	(footprint ""
		(layer "F.Cu")
		(at 460.174594 -45.477176 -90)
		(property "Reference" "R6099"
			(at 0 0 270)
			(layer "F.SilkS")
			(hide yes)
			(effects
				(font
					(size 1.27 1.27)
				)
			)
		)
		(property "Value" ""
			(at 0 0 270)
			(layer "F.Fab")
			(effects
				(font
					(size 1.27 1.27)
				)
			)
		)
		(duplicate_pad_numbers_are_jumpers no)
		(fp_line
			(start -0.7874 0.4064)
			(end -0.7874 -0.4064)
			(stroke
				(width 0.1524)
				(type default)
			)
			(layer "F.SilkS")
		)
		(fp_line
			(start 0.7874 0.4064)
			(end -0.7874 0.4064)
			(stroke
				(width 0.1524)
				(type default)
			)
			(layer "F.SilkS")
		)
		(fp_line
			(start -0.7874 -0.4064)
			(end 0.7874 -0.4064)
			(stroke
				(width 0.1524)
				(type default)
			)
			(layer "F.SilkS")
		)
		(fp_line
			(start 0.7874 -0.4064)
			(end 0.7874 0.4064)
			(stroke
				(width 0.1524)
				(type default)
			)
			(layer "F.SilkS")
		)
		(fp_line
			(start -0.67945 0.3048)
			(end -0.67945 -0.305054)
			(stroke
				(width 0.1)
				(type default)
			)
			(layer "F.Fab")
		)
		(fp_line
			(start -0.12065 0.3048)
			(end -0.67945 0.3048)
			(stroke
				(width 0.1)
				(type default)
			)
			(layer "F.Fab")
		)
		(fp_line
			(start 0.120396 0.3048)
			(end 0.120396 0.2794)
			(stroke
				(width 0.1)
				(type default)
			)
			(layer "F.Fab")
		)
		(fp_line
			(start 0.67945 0.3048)
			(end 0.120396 0.3048)
			(stroke
				(width 0.1)
				(type default)
			)
			(layer "F.Fab")
		)
		(fp_line
			(start -0.12065 0.2794)
			(end -0.12065 0.3048)
			(stroke
				(width 0.1)
				(type default)
			)
			(layer "F.Fab")
		)
		(fp_line
			(start 0.120396 0.2794)
			(end -0.12065 0.2794)
			(stroke
				(width 0.1)
				(type default)
			)
			(layer "F.Fab")
		)
		(fp_line
			(start -0.12065 -0.2794)
			(end 0.12065 -0.2794)
			(stroke
				(width 0.1)
				(type default)
			)
			(layer "F.Fab")
		)
		(fp_line
			(start 0.12065 -0.2794)
			(end 0.12065 -0.3048)
			(stroke
				(width 0.1)
				(type default)
			)
			(layer "F.Fab")
		)
		(fp_line
			(start 0.12065 -0.3048)
			(end 0.67945 -0.3048)
			(stroke
				(width 0.1)
				(type default)
			)
			(layer "F.Fab")
		)
		(fp_line
			(start 0.67945 -0.3048)
			(end 0.67945 0.3048)
			(stroke
				(width 0.1)
				(type default)
			)
			(layer "F.Fab")
		)
		(fp_line
			(start -0.67945 -0.305054)
			(end -0.12065 -0.305054)
			(stroke
				(width 0.1)
				(type default)
			)
			(layer "F.Fab")
		)
		(fp_line
			(start -0.12065 -0.305054)
			(end -0.12065 -0.2794)
			(stroke
				(width 0.1)
				(type default)
			)
			(layer "F.Fab")
		)
		(pad "1" smd circle
			(at -0.40005 0 270)
			(size 0 0)
			(layers "F.Cu" "F.Mask" "F.Paste")
			(net "PWRGD_P3V3_AUX_R1")
		)
		(pad "2" smd circle
			(at 0.40005 0 270)
			(size 0 0)
			(layers "F.Cu" "F.Mask" "F.Paste")
			(net "PWRGD_P3V3_AUX")
		)
	)
	(footprint ""
		(layer "F.Cu")
		(at 453.169782 -41.757346 90)
		(property "Reference" "R1136"
			(at 0 0 90)
			(layer "F.SilkS")
			(hide yes)
			(effects
				(font
					(size 1.27 1.27)
				)
			)
		)
		(property "Value" ""
			(at 0 0 90)
			(layer "F.Fab")
			(effects
				(font
					(size 1.27 1.27)
				)
			)
		)
		(duplicate_pad_numbers_are_jumpers no)
		(fp_line
			(start 0.7874 -0.4064)
			(end 0.7874 0.4064)
			(stroke
				(width 0.1524)
				(type default)
			)
			(layer "F.SilkS")
		)
		(fp_line
			(start -0.7874 -0.4064)
			(end 0.7874 -0.4064)
			(stroke
				(width 0.1524)
				(type default)
			)
			(layer "F.SilkS")
		)
		(fp_line
			(start 0.7874 0.4064)
			(end -0.7874 0.4064)
			(stroke
				(width 0.1524)
				(type default)
			)
			(layer "F.SilkS")
		)
		(fp_line
			(start -0.7874 0.4064)
			(end -0.7874 -0.4064)
			(stroke
				(width 0.1524)
				(type default)
			)
			(layer "F.SilkS")
		)
		(fp_line
			(start -0.12065 -0.305054)
			(end -0.12065 -0.2794)
			(stroke
				(width 0.1)
				(type default)
			)
			(layer "F.Fab")
		)
		(fp_line
			(start -0.67945 -0.305054)
			(end -0.12065 -0.305054)
			(stroke
				(width 0.1)
				(type default)
			)
			(layer "F.Fab")
		)
		(fp_line
			(start 0.67945 -0.3048)
			(end 0.67945 0.3048)
			(stroke
				(width 0.1)
				(type default)
			)
			(layer "F.Fab")
		)
		(fp_line
			(start 0.12065 -0.3048)
			(end 0.67945 -0.3048)
			(stroke
				(width 0.1)
				(type default)
			)
			(layer "F.Fab")
		)
		(fp_line
			(start 0.12065 -0.2794)
			(end 0.12065 -0.3048)
			(stroke
				(width 0.1)
				(type default)
			)
			(layer "F.Fab")
		)
		(fp_line
			(start -0.12065 -0.2794)
			(end 0.12065 -0.2794)
			(stroke
				(width 0.1)
				(type default)
			)
			(layer "F.Fab")
		)
		(fp_line
			(start 0.120396 0.2794)
			(end -0.12065 0.2794)
			(stroke
				(width 0.1)
				(type default)
			)
			(layer "F.Fab")
		)
		(fp_line
			(start -0.12065 0.2794)
			(end -0.12065 0.3048)
			(stroke
				(width 0.1)
				(type default)
			)
			(layer "F.Fab")
		)
		(fp_line
			(start 0.67945 0.3048)
			(end 0.120396 0.3048)
			(stroke
				(width 0.1)
				(type default)
			)
			(layer "F.Fab")
		)
		(fp_line
			(start 0.120396 0.3048)
			(end 0.120396 0.2794)
			(stroke
				(width 0.1)
				(type default)
			)
			(layer "F.Fab")
		)
		(fp_line
			(start -0.12065 0.3048)
			(end -0.67945 0.3048)
			(stroke
				(width 0.1)
				(type default)
			)
			(layer "F.Fab")
		)
		(fp_line
			(start -0.67945 0.3048)
			(end -0.67945 -0.305054)
			(stroke
				(width 0.1)
				(type default)
			)
			(layer "F.Fab")
		)
		(pad "1" smd circle
			(at -0.40005 0 90)
			(size 0 0)
			(layers "F.Cu" "F.Mask" "F.Paste")
			(net "HP_LVC3_OCP_V3_1_P12V_PWRGD")
		)
		(pad "2" smd circle
			(at 0.40005 0 90)
			(size 0 0)
			(layers "F.Cu" "F.Mask" "F.Paste")
			(net "P3V3_OCP_EN_1_R")
		)
	)
	(footprint ""
		(layer "F.Cu")
		(at 305.819048 -46.021498)
		(property "Reference" "R3671"
			(at 0 0 0)
			(layer "F.SilkS")
			(hide yes)
			(effects
				(font
					(size 1.27 1.27)
				)
			)
		)
		(property "Value" ""
			(at 0 0 0)
			(layer "F.Fab")
			(effects
				(font
					(size 1.27 1.27)
				)
			)
		)
		(duplicate_pad_numbers_are_jumpers no)
		(fp_line
			(start -0.7874 -0.4064)
			(end 0.7874 -0.4064)
			(stroke
				(width 0.1524)
				(type default)
			)
			(layer "F.SilkS")
		)
		(fp_line
			(start -0.7874 0.4064)
			(end -0.7874 -0.4064)
			(stroke
				(width 0.1524)
				(type default)
			)
			(layer "F.SilkS")
		)
		(fp_line
			(start 0.7874 -0.4064)
			(end 0.7874 0.4064)
			(stroke
				(width 0.1524)
				(type default)
			)
			(layer "F.SilkS")
		)
		(fp_line
			(start 0.7874 0.4064)
			(end -0.7874 0.4064)
			(stroke
				(width 0.1524)
				(type default)
			)
			(layer "F.SilkS")
		)
		(fp_line
			(start -0.67945 -0.305054)
			(end -0.12065 -0.305054)
			(stroke
				(width 0.1)
				(type default)
			)
			(layer "F.Fab")
		)
		(fp_line
			(start -0.67945 0.3048)
			(end -0.67945 -0.305054)
			(stroke
				(width 0.1)
				(type default)
			)
			(layer "F.Fab")
		)
		(fp_line
			(start -0.12065 -0.305054)
			(end -0.12065 -0.2794)
			(stroke
				(width 0.1)
				(type default)
			)
			(layer "F.Fab")
		)
		(fp_line
			(start -0.12065 -0.2794)
			(end 0.12065 -0.2794)
			(stroke
				(width 0.1)
				(type default)
			)
			(layer "F.Fab")
		)
		(fp_line
			(start -0.12065 0.2794)
			(end -0.12065 0.3048)
			(stroke
				(width 0.1)
				(type default)
			)
			(layer "F.Fab")
		)
		(fp_line
			(start -0.12065 0.3048)
			(end -0.67945 0.3048)
			(stroke
				(width 0.1)
				(type default)
			)
			(layer "F.Fab")
		)
		(fp_line
			(start 0.120396 0.2794)
			(end -0.12065 0.2794)
			(stroke
				(width 0.1)
				(type default)
			)
			(layer "F.Fab")
		)
		(fp_line
			(start 0.120396 0.3048)
			(end 0.120396 0.2794)
			(stroke
				(width 0.1)
				(type default)
			)
			(layer "F.Fab")
		)
		(fp_line
			(start 0.12065 -0.3048)
			(end 0.67945 -0.3048)
			(stroke
				(width 0.1)
				(type default)
			)
			(layer "F.Fab")
		)
		(fp_line
			(start 0.12065 -0.2794)
			(end 0.12065 -0.3048)
			(stroke
				(width 0.1)
				(type default)
			)
			(layer "F.Fab")
		)
		(fp_line
			(start 0.67945 -0.3048)
			(end 0.67945 0.3048)
			(stroke
				(width 0.1)
				(type default)
			)
			(layer "F.Fab")
		)
		(fp_line
			(start 0.67945 0.3048)
			(end 0.120396 0.3048)
			(stroke
				(width 0.1)
				(type default)
			)
			(layer "F.Fab")
		)
		(pad "1" smd circle
			(at -0.40005 0)
			(size 0 0)
			(layers "F.Cu" "F.Mask" "F.Paste")
			(net "SMB_SCM_2_R4_SDA")
		)
		(pad "2" smd circle
			(at 0.40005 0)
			(size 0 0)
			(layers "F.Cu" "F.Mask" "F.Paste")
			(net "SMB_SEN_TIC_3V3AUX_SDA")
		)
	)
	(footprint ""
		(layer "F.Cu")
		(at 257.85953 -55.479442)
		(property "Reference" "PR3949"
			(at 0 0 0)
			(layer "F.SilkS")
			(hide yes)
			(effects
				(font
					(size 1.27 1.27)
				)
			)
		)
		(property "Value" ""
			(at 0 0 0)
			(layer "F.Fab")
			(effects
				(font
					(size 1.27 1.27)
				)
			)
		)
		(duplicate_pad_numbers_are_jumpers no)
		(fp_line
			(start -0.7874 -0.4064)
			(end 0.7874 -0.4064)
			(stroke
				(width 0.1524)
				(type default)
			)
			(layer "F.SilkS")
		)
		(fp_line
			(start -0.7874 0.4064)
			(end -0.7874 -0.4064)
			(stroke
				(width 0.1524)
				(type default)
			)
			(layer "F.SilkS")
		)
		(fp_line
			(start 0.7874 -0.4064)
			(end 0.7874 0.4064)
			(stroke
				(width 0.1524)
				(type default)
			)
			(layer "F.SilkS")
		)
		(fp_line
			(start 0.7874 0.4064)
			(end -0.7874 0.4064)
			(stroke
				(width 0.1524)
				(type default)
			)
			(layer "F.SilkS")
		)
		(fp_line
			(start -0.67945 -0.305054)
			(end -0.12065 -0.305054)
			(stroke
				(width 0.1)
				(type default)
			)
			(layer "F.Fab")
		)
		(fp_line
			(start -0.67945 0.3048)
			(end -0.67945 -0.305054)
			(stroke
				(width 0.1)
				(type default)
			)
			(layer "F.Fab")
		)
		(fp_line
			(start -0.12065 -0.305054)
			(end -0.12065 -0.2794)
			(stroke
				(width 0.1)
				(type default)
			)
			(layer "F.Fab")
		)
		(fp_line
			(start -0.12065 -0.2794)
			(end 0.12065 -0.2794)
			(stroke
				(width 0.1)
				(type default)
			)
			(layer "F.Fab")
		)
		(fp_line
			(start -0.12065 0.2794)
			(end -0.12065 0.3048)
			(stroke
				(width 0.1)
				(type default)
			)
			(layer "F.Fab")
		)
		(fp_line
			(start -0.12065 0.3048)
			(end -0.67945 0.3048)
			(stroke
				(width 0.1)
				(type default)
			)
			(layer "F.Fab")
		)
		(fp_line
			(start 0.120396 0.2794)
			(end -0.12065 0.2794)
			(stroke
				(width 0.1)
				(type default)
			)
			(layer "F.Fab")
		)
		(fp_line
			(start 0.120396 0.3048)
			(end 0.120396 0.2794)
			(stroke
				(width 0.1)
				(type default)
			)
			(layer "F.Fab")
		)
		(fp_line
			(start 0.12065 -0.3048)
			(end 0.67945 -0.3048)
			(stroke
				(width 0.1)
				(type default)
			)
			(layer "F.Fab")
		)
		(fp_line
			(start 0.12065 -0.2794)
			(end 0.12065 -0.3048)
			(stroke
				(width 0.1)
				(type default)
			)
			(layer "F.Fab")
		)
		(fp_line
			(start 0.67945 -0.3048)
			(end 0.67945 0.3048)
			(stroke
				(width 0.1)
				(type default)
			)
			(layer "F.Fab")
		)
		(fp_line
			(start 0.67945 0.3048)
			(end 0.120396 0.3048)
			(stroke
				(width 0.1)
				(type default)
			)
			(layer "F.Fab")
		)
		(pad "1" smd circle
			(at -0.40005 0)
			(size 0 0)
			(layers "F.Cu" "F.Mask" "F.Paste")
			(net "P12V_E1S_IMON_0")
		)
		(pad "2" smd circle
			(at 0.40005 0)
			(size 0 0)
			(layers "F.Cu" "F.Mask" "F.Paste")
			(net "GND")
		)
	)
	(footprint ""
		(layer "F.Cu")
		(at 167.11676 -117.301772)
		(property "Reference" "R6137"
			(at 0 0 0)
			(layer "F.SilkS")
			(hide yes)
			(effects
				(font
					(size 1.27 1.27)
				)
			)
		)
		(property "Value" ""
			(at 0 0 0)
			(layer "F.Fab")
			(effects
				(font
					(size 1.27 1.27)
				)
			)
		)
		(duplicate_pad_numbers_are_jumpers no)
		(fp_line
			(start -0.7874 -0.4064)
			(end 0.7874 -0.4064)
			(stroke
				(width 0.1524)
				(type default)
			)
			(layer "F.SilkS")
		)
		(fp_line
			(start -0.7874 0.4064)
			(end -0.7874 -0.4064)
			(stroke
				(width 0.1524)
				(type default)
			)
			(layer "F.SilkS")
		)
		(fp_line
			(start 0.7874 -0.4064)
			(end 0.7874 0.4064)
			(stroke
				(width 0.1524)
				(type default)
			)
			(layer "F.SilkS")
		)
		(fp_line
			(start 0.7874 0.4064)
			(end -0.7874 0.4064)
			(stroke
				(width 0.1524)
				(type default)
			)
			(layer "F.SilkS")
		)
		(fp_line
			(start -0.67945 -0.305054)
			(end -0.12065 -0.305054)
			(stroke
				(width 0.1)
				(type default)
			)
			(layer "F.Fab")
		)
		(fp_line
			(start -0.67945 0.3048)
			(end -0.67945 -0.305054)
			(stroke
				(width 0.1)
				(type default)
			)
			(layer "F.Fab")
		)
		(fp_line
			(start -0.12065 -0.305054)
			(end -0.12065 -0.2794)
			(stroke
				(width 0.1)
				(type default)
			)
			(layer "F.Fab")
		)
		(fp_line
			(start -0.12065 -0.2794)
			(end 0.12065 -0.2794)
			(stroke
				(width 0.1)
				(type default)
			)
			(layer "F.Fab")
		)
		(fp_line
			(start -0.12065 0.2794)
			(end -0.12065 0.3048)
			(stroke
				(width 0.1)
				(type default)
			)
			(layer "F.Fab")
		)
		(fp_line
			(start -0.12065 0.3048)
			(end -0.67945 0.3048)
			(stroke
				(width 0.1)
				(type default)
			)
			(layer "F.Fab")
		)
		(fp_line
			(start 0.120396 0.2794)
			(end -0.12065 0.2794)
			(stroke
				(width 0.1)
				(type default)
			)
			(layer "F.Fab")
		)
		(fp_line
			(start 0.120396 0.3048)
			(end 0.120396 0.2794)
			(stroke
				(width 0.1)
				(type default)
			)
			(layer "F.Fab")
		)
		(fp_line
			(start 0.12065 -0.3048)
			(end 0.67945 -0.3048)
			(stroke
				(width 0.1)
				(type default)
			)
			(layer "F.Fab")
		)
		(fp_line
			(start 0.12065 -0.2794)
			(end 0.12065 -0.3048)
			(stroke
				(width 0.1)
				(type default)
			)
			(layer "F.Fab")
		)
		(fp_line
			(start 0.67945 -0.3048)
			(end 0.67945 0.3048)
			(stroke
				(width 0.1)
				(type default)
			)
			(layer "F.Fab")
		)
		(fp_line
			(start 0.67945 0.3048)
			(end 0.120396 0.3048)
			(stroke
				(width 0.1)
				(type default)
			)
			(layer "F.Fab")
		)
		(pad "1" smd circle
			(at -0.40005 0)
			(size 0 0)
			(layers "F.Cu" "F.Mask" "F.Paste")
			(net "P3V3_AUX")
		)
		(pad "2" smd circle
			(at 0.40005 0)
			(size 0 0)
			(layers "F.Cu" "F.Mask" "F.Paste")
			(net "FM_BOARD_BMC_SKU_ID3")
		)
	)
)
